# S9S_MB_2U (Grand Teton) — schematic netlist excerpt (pin names and nets, part order shuffled) for the footprints in the layout excerpt that follows; sources: Cadence DE-HDL packaged netlist, KiCad conversion of 03242023_DA0F0TMBIJ0_F0T_Motherboard_J_brd_V01_OCP.brd

PC594  Q_CAP  3300PF 50V 10% X7R  pkg 0402  page 266 : A = SH_PVCCFA_EHV_FIVRA_CPU0_R ; B = VSENSE_PVCCFA_EHV_FIVRA_CPU0_DN
R1594  Q_RES  33.2 1% CHIP  pkg 0402LF  page 155 : A = OCP_SFF_WAKE_BUFF_N ; B = OCP_SFF_WAKE_BUFF_R_N

(kicad_pcb
	(version 20260206)
	(generator "pcbnew")
	(generator_version "10.0")
	(general
		(thickness 1.6)
		(legacy_teardrops no)
	)
	(paper "A4")
	(title_block
		(title "03242023_DA0F0TMBIJ0_F0T_Motherboard_J_brd_V01_OCP.brd")
		(comment 1 "Grand Teton / footprints 1542-1543 of 6105")
	)
	(layers
		(0 "F.Cu" signal "TOP")
		(4 "In1.Cu" signal "GND")
		(6 "In2.Cu" signal "IN1")
		(8 "In3.Cu" signal "GND1")
		(10 "In4.Cu" signal "IN2")
		(12 "In5.Cu" signal "GND2")
		(14 "In6.Cu" signal "IN3")
		(16 "In7.Cu" signal "GND3")
		(18 "In8.Cu" signal "VCC")
		(20 "In9.Cu" signal "VCC1")
		(22 "In10.Cu" signal "GND4")
		(24 "In11.Cu" signal "IN4")
		(26 "In12.Cu" signal "GND5")
		(28 "In13.Cu" signal "IN5")
		(30 "In14.Cu" signal "GND6")
		(32 "In15.Cu" signal "IN6")
		(34 "In16.Cu" signal "GND7")
		(2 "B.Cu" signal "BOTTOM")
		(9 "F.Adhes" user "F.Adhesive")
		(11 "B.Adhes" user "B.Adhesive")
		(13 "F.Paste" user "Package Geometry/Pastemask Top")
		(15 "B.Paste" user "Package Geometry/Pastemask Bottom")
		(5 "F.SilkS" user "Ref Des/Silkscreen Top")
		(7 "B.SilkS" user "Ref Des/Silkscreen Bottom")
		(1 "F.Mask" user "Board Geometry/Soldermask Top")
		(3 "B.Mask" user "Board Geometry/Soldermask Bottom")
		(17 "Dwgs.User" user "User.Drawings")
		(19 "Cmts.User" user "User.Comments")
		(21 "Eco1.User" user "User.Eco1")
		(23 "Eco2.User" user "User.Eco2")
		(25 "Edge.Cuts" user "Board Geometry/Outline")
		(27 "Margin" user)
		(31 "F.CrtYd" user "Package Geometry/Place Bound Top")
		(29 "B.CrtYd" user "Package Geometry/Place Bound Bottom")
		(35 "F.Fab" user "Ref Des/Assembly Top")
		(33 "B.Fab" user "Ref Des/Assembly Bottom")
	)
	(footprint ""
		(layer "F.Cu")
		(at 468.49157 -44.887388)
		(property "Reference" "R1594"
			(at 0 0 0)
			(layer "F.SilkS")
			(hide yes)
			(effects
				(font
					(size 1.27 1.27)
				)
			)
		)
		(property "Value" ""
			(at 0 0 0)
			(layer "F.Fab")
			(effects
				(font
					(size 1.27 1.27)
				)
			)
		)
		(duplicate_pad_numbers_are_jumpers no)
		(fp_line
			(start -0.7874 -0.4064)
			(end 0.7874 -0.4064)
			(stroke
				(width 0.1524)
				(type default)
			)
			(layer "F.SilkS")
		)
		(fp_line
			(start -0.7874 0.4064)
			(end -0.7874 -0.4064)
			(stroke
				(width 0.1524)
				(type default)
			)
			(layer "F.SilkS")
		)
		(fp_line
			(start 0.7874 -0.4064)
			(end 0.7874 0.4064)
			(stroke
				(width 0.1524)
				(type default)
			)
			(layer "F.SilkS")
		)
		(fp_line
			(start 0.7874 0.4064)
			(end -0.7874 0.4064)
			(stroke
				(width 0.1524)
				(type default)
			)
			(layer "F.SilkS")
		)
		(fp_line
			(start -0.67945 -0.305054)
			(end -0.12065 -0.305054)
			(stroke
				(width 0.1)
				(type default)
			)
			(layer "F.Fab")
		)
		(fp_line
			(start -0.67945 0.3048)
			(end -0.67945 -0.305054)
			(stroke
				(width 0.1)
				(type default)
			)
			(layer "F.Fab")
		)
		(fp_line
			(start -0.12065 -0.305054)
			(end -0.12065 -0.2794)
			(stroke
				(width 0.1)
				(type default)
			)
			(layer "F.Fab")
		)
		(fp_line
			(start -0.12065 -0.2794)
			(end 0.12065 -0.2794)
			(stroke
				(width 0.1)
				(type default)
			)
			(layer "F.Fab")
		)
		(fp_line
			(start -0.12065 0.2794)
			(end -0.12065 0.3048)
			(stroke
				(width 0.1)
				(type default)
			)
			(layer "F.Fab")
		)
		(fp_line
			(start -0.12065 0.3048)
			(end -0.67945 0.3048)
			(stroke
				(width 0.1)
				(type default)
			)
			(layer "F.Fab")
		)
		(fp_line
			(start 0.120396 0.2794)
			(end -0.12065 0.2794)
			(stroke
				(width 0.1)
				(type default)
			)
			(layer "F.Fab")
		)
		(fp_line
			(start 0.120396 0.3048)
			(end 0.120396 0.2794)
			(stroke
				(width 0.1)
				(type default)
			)
			(layer "F.Fab")
		)
		(fp_line
			(start 0.12065 -0.3048)
			(end 0.67945 -0.3048)
			(stroke
				(width 0.1)
				(type default)
			)
			(layer "F.Fab")
		)
		(fp_line
			(start 0.12065 -0.2794)
			(end 0.12065 -0.3048)
			(stroke
				(width 0.1)
				(type default)
			)
			(layer "F.Fab")
		)
		(fp_line
			(start 0.67945 -0.3048)
			(end 0.67945 0.3048)
			(stroke
				(width 0.1)
				(type default)
			)
			(layer "F.Fab")
		)
		(fp_line
			(start 0.67945 0.3048)
			(end 0.120396 0.3048)
			(stroke
				(width 0.1)
				(type default)
			)
			(layer "F.Fab")
		)
		(pad "1" smd circle
			(at -0.40005 0)
			(size 0 0)
			(layers "F.Cu" "F.Mask" "F.Paste")
			(net "OCP_SFF_WAKE_BUFF_N")
		)
		(pad "2" smd circle
			(at 0.40005 0)
			(size 0 0)
			(layers "F.Cu" "F.Mask" "F.Paste")
			(net "OCP_SFF_WAKE_BUFF_R_N")
		)
	)
	(footprint ""
		(layer "F.Cu")
		(at 362.89742 -354.065586)
		(property "Reference" "PC594"
			(at 0 0 0)
			(layer "F.SilkS")
			(hide yes)
			(effects
				(font
					(size 1.27 1.27)
				)
			)
		)
		(property "Value" ""
			(at 0 0 0)
			(layer "F.Fab")
			(effects
				(font
					(size 1.27 1.27)
				)
			)
		)
		(duplicate_pad_numbers_are_jumpers no)
		(fp_line
			(start -0.7874 -0.4064)
			(end 0.7874 -0.4064)
			(stroke
				(width 0.1524)
				(type default)
			)
			(layer "F.SilkS")
		)
		(fp_line
			(start -0.7874 0.4064)
			(end -0.7874 -0.4064)
			(stroke
				(width 0.1524)
				(type default)
			)
			(layer "F.SilkS")
		)
		(fp_line
			(start 0.7874 -0.4064)
			(end 0.7874 0.4064)
			(stroke
				(width 0.1524)
				(type default)
			)
			(layer "F.SilkS")
		)
		(fp_line
			(start 0.7874 0.4064)
			(end -0.7874 0.4064)
			(stroke
				(width 0.1524)
				(type default)
			)
			(layer "F.SilkS")
		)
		(fp_line
			(start -0.67945 -0.305054)
			(end -0.12065 -0.305054)
			(stroke
				(width 0.1)
				(type default)
			)
			(layer "F.Fab")
		)
		(fp_line
			(start -0.67945 0.3048)
			(end -0.67945 -0.305054)
			(stroke
				(width 0.1)
				(type default)
			)
			(layer "F.Fab")
		)
		(fp_line
			(start -0.12065 -0.305054)
			(end -0.12065 -0.2794)
			(stroke
				(width 0.1)
				(type default)
			)
			(layer "F.Fab")
		)
		(fp_line
			(start -0.12065 -0.2794)
			(end 0.12065 -0.2794)
			(stroke
				(width 0.1)
				(type default)
			)
			(layer "F.Fab")
		)
		(fp_line
			(start -0.12065 0.2794)
			(end -0.12065 0.3048)
			(stroke
				(width 0.1)
				(type default)
			)
			(layer "F.Fab")
		)
		(fp_line
			(start -0.12065 0.3048)
			(end -0.67945 0.3048)
			(stroke
				(width 0.1)
				(type default)
			)
			(layer "F.Fab")
		)
		(fp_line
			(start 0.120396 0.2794)
			(end -0.12065 0.2794)
			(stroke
				(width 0.1)
				(type default)
			)
			(layer "F.Fab")
		)
		(fp_line
			(start 0.120396 0.3048)
			(end 0.120396 0.2794)
			(stroke
				(width 0.1)
				(type default)
			)
			(layer "F.Fab")
		)
		(fp_line
			(start 0.12065 -0.3048)
			(end 0.67945 -0.3048)
			(stroke
				(width 0.1)
				(type default)
			)
			(layer "F.Fab")
		)
		(fp_line
			(start 0.12065 -0.2794)
			(end 0.12065 -0.3048)
			(stroke
				(width 0.1)
				(type default)
			)
			(layer "F.Fab")
		)
		(fp_line
			(start 0.67945 -0.3048)
			(end 0.67945 0.3048)
			(stroke
				(width 0.1)
				(type default)
			)
			(layer "F.Fab")
		)
		(fp_line
			(start 0.67945 0.3048)
			(end 0.120396 0.3048)
			(stroke
				(width 0.1)
				(type default)
			)
			(layer "F.Fab")
		)
		(pad "1" smd circle
			(at -0.40005 0)
			(size 0 0)
			(layers "F.Cu" "F.Mask" "F.Paste")
			(net "SH_PVCCFA_EHV_FIVRA_CPU0_R")
		)
		(pad "2" smd circle
			(at 0.40005 0)
			(size 0 0)
			(layers "F.Cu" "F.Mask" "F.Paste")
			(net "VSENSE_PVCCFA_EHV_FIVRA_CPU0_DN")
		)
	)
)
